# T6G (Grand Teton) — schematic netlist excerpt (pin names and nets, part order shuffled) for the footprints in the layout excerpt that follows; sources: Cadence DE-HDL packaged netlist, KiCad conversion of 04192023_DAF0TMB3IC0_F0TG_MB_C_brd_V02_OCP.brd

Q8000  MOSFET_NCH_DUAL  PJT138K IC  pkg SOT363XD  page 123
  S1  = GND
  G1  = PRSNT_SWB_N
  D2  = PRSNT_SWB_ISO_N
  S2  = GND
  G2  = PRSNT_SWB
  D1  = PRSNT_SWB

PC1868  Q_CAP  22UF 10V 20% X6S  pkg C0805  page 190 : A = P3V3_AUX ; B = GND

(kicad_pcb
	(version 20260206)
	(generator "pcbnew")
	(generator_version "10.0")
	(general
		(thickness 1.6)
		(legacy_teardrops no)
	)
	(paper "A4")
	(title_block
		(title "04192023_DAF0TMB3IC0_F0TG_MB_C_brd_V02_OCP.brd")
		(comment 1 "Grand Teton / footprints 4967-4968 of 8354")
	)
	(layers
		(0 "F.Cu" signal "TOP")
		(4 "In1.Cu" signal "GND")
		(6 "In2.Cu" signal "IN1")
		(8 "In3.Cu" signal "GND1")
		(10 "In4.Cu" signal "IN2")
		(12 "In5.Cu" signal "GND2")
		(14 "In6.Cu" signal "IN3")
		(16 "In7.Cu" signal "GND3")
		(18 "In8.Cu" signal "VCC")
		(20 "In9.Cu" signal "VCC1")
		(22 "In10.Cu" signal "GND4")
		(24 "In11.Cu" signal "IN4")
		(26 "In12.Cu" signal "GND5")
		(28 "In13.Cu" signal "IN5")
		(30 "In14.Cu" signal "GND6")
		(32 "In15.Cu" signal "IN6")
		(34 "In16.Cu" signal "GND7")
		(2 "B.Cu" signal "BOTTOM")
		(9 "F.Adhes" user "F.Adhesive")
		(11 "B.Adhes" user "B.Adhesive")
		(13 "F.Paste" user "Package Geometry/Pastemask Top")
		(15 "B.Paste" user "Package Geometry/Pastemask Bottom")
		(5 "F.SilkS" user "Ref Des/Silkscreen Top")
		(7 "B.SilkS" user "Ref Des/Silkscreen Bottom")
		(1 "F.Mask" user "Board Geometry/Soldermask Top")
		(3 "B.Mask" user "Board Geometry/Soldermask Bottom")
		(17 "Dwgs.User" user "User.Drawings")
		(19 "Cmts.User" user "User.Comments")
		(21 "Eco1.User" user "User.Eco1")
		(23 "Eco2.User" user "User.Eco2")
		(25 "Edge.Cuts" user "Board Geometry/Outline")
		(27 "Margin" user)
		(31 "F.CrtYd" user "Package Geometry/Place Bound Top")
		(29 "B.CrtYd" user "Package Geometry/Place Bound Bottom")
		(35 "F.Fab" user "Ref Des/Assembly Top")
		(33 "B.Fab" user "Ref Des/Assembly Bottom")
	)
	(footprint ""
		(layer "B.Cu")
		(at 452.957184 -65.768982 90)
		(property "Reference" "PC1868"
			(at 0 0 90)
			(layer "B.SilkS")
			(hide yes)
			(effects
				(font
					(size 1.27 1.27)
				)
				(justify mirror)
			)
		)
		(property "Value" ""
			(at 0 0 90)
			(layer "B.Fab")
			(effects
				(font
					(size 1.27 1.27)
				)
				(justify mirror)
			)
		)
		(duplicate_pad_numbers_are_jumpers no)
		(fp_line
			(start 1.524 -0.762)
			(end -1.524 -0.762)
			(stroke
				(width 0.1524)
				(type default)
			)
			(layer "B.SilkS")
		)
		(fp_line
			(start -1.524 -0.762)
			(end -1.524 0.762)
			(stroke
				(width 0.1524)
				(type default)
			)
			(layer "B.SilkS")
		)
		(fp_line
			(start 1.524 0.762)
			(end 1.524 -0.762)
			(stroke
				(width 0.1524)
				(type default)
			)
			(layer "B.SilkS")
		)
		(fp_line
			(start -1.524 0.762)
			(end 1.524 0.762)
			(stroke
				(width 0.1524)
				(type default)
			)
			(layer "B.SilkS")
		)
		(fp_line
			(start 1.1049 -0.724916)
			(end 1.1049 0.724916)
			(stroke
				(width 0.1)
				(type default)
			)
			(layer "B.Fab")
		)
		(fp_line
			(start -1.1049 -0.724916)
			(end 1.1049 -0.724916)
			(stroke
				(width 0.1)
				(type default)
			)
			(layer "B.Fab")
		)
		(fp_line
			(start 1.1049 0.724916)
			(end -1.1049 0.724916)
			(stroke
				(width 0.1)
				(type default)
			)
			(layer "B.Fab")
		)
		(fp_line
			(start -1.1049 0.724916)
			(end -1.1049 -0.724916)
			(stroke
				(width 0.1)
				(type default)
			)
			(layer "B.Fab")
		)
		(pad "1" smd rect
			(at 0.889 0 90)
			(size 1.016 1.27)
			(layers "B.Cu" "B.Mask" "B.Paste")
			(net "P3V3_AUX")
		)
		(pad "2" smd rect
			(at -0.889 0 90)
			(size 1.016 1.27)
			(layers "B.Cu" "B.Mask" "B.Paste")
			(net "GND")
		)
	)
	(footprint ""
		(layer "B.Cu")
		(at 101.073204 -424.885358 180)
		(property "Reference" "Q8000"
			(at -1.528826 -2.694686 0)
			(unlocked yes)
			(layer "B.SilkS")
			(effects
				(font
					(size 0.7874 0.5842)
					(thickness 0.1524)
				)
				(justify left mirror)
			)
		)
		(property "Value" ""
			(at 0 0 0)
			(layer "B.Fab")
			(effects
				(font
					(size 1.27 1.27)
				)
				(justify mirror)
			)
		)
		(duplicate_pad_numbers_are_jumpers no)
		(fp_line
			(start 1.332738 1.100074)
			(end 1.332738 -1.100074)
			(stroke
				(width 0.1524)
				(type default)
			)
			(layer "B.SilkS")
		)
		(fp_line
			(start 1.332738 -1.100074)
			(end 0.4826 -1.100074)
			(stroke
				(width 0.1524)
				(type default)
			)
			(layer "B.SilkS")
		)
		(fp_line
			(start 0.4826 -1.100074)
			(end 0 -0.541274)
			(stroke
				(width 0.1524)
				(type default)
			)
			(layer "B.SilkS")
		)
		(fp_line
			(start 0 -0.541274)
			(end -0.4826 -1.100074)
			(stroke
				(width 0.1524)
				(type default)
			)
			(layer "B.SilkS")
		)
		(fp_line
			(start -0.4826 -1.100074)
			(end -1.332738 -1.100074)
			(stroke
				(width 0.1524)
				(type default)
			)
			(layer "B.SilkS")
		)
		(fp_line
			(start -1.332738 1.100074)
			(end 1.332738 1.100074)
			(stroke
				(width 0.1524)
				(type default)
			)
			(layer "B.SilkS")
		)
		(fp_line
			(start -1.332738 -1.100074)
			(end -1.332738 1.100074)
			(stroke
				(width 0.1524)
				(type default)
			)
			(layer "B.SilkS")
		)
		(fp_poly
			(pts
				(xy 2.2352 -0.298958) (xy 2.2352 -1.001014) (xy 1.533144 -0.649986)
			)
			(stroke
				(width 0)
				(type default)
			)
			(fill yes)
			(layer "B.SilkS")
		)
		(fp_line
			(start 0.674878 1.100074)
			(end 0.674878 -1.100074)
			(stroke
				(width 0.1)
				(type default)
			)
			(layer "B.Fab")
		)
		(fp_line
			(start 0.674878 -1.100074)
			(end -0.674878 -1.100074)
			(stroke
				(width 0.1)
				(type default)
			)
			(layer "B.Fab")
		)
		(fp_line
			(start -0.674878 1.100074)
			(end 0.674878 1.100074)
			(stroke
				(width 0.1)
				(type default)
			)
			(layer "B.Fab")
		)
		(fp_line
			(start -0.674878 -1.100074)
			(end -0.674878 1.100074)
			(stroke
				(width 0.1)
				(type default)
			)
			(layer "B.Fab")
		)
		(fp_poly
			(pts
				(xy 2.2352 -0.298958) (xy 2.2352 -1.001014) (xy 1.533144 -0.649986)
			)
			(stroke
				(width 0)
				(type default)
			)
			(fill yes)
			(layer "B.Fab")
		)
		(pad "1" smd rect
			(at 0.94996 -0.649986 270)
			(size 0.4318 0.508)
			(layers "B.Cu" "B.Mask" "B.Paste")
			(net "GND")
		)
		(pad "2" smd rect
			(at 0.94996 0 270)
			(size 0.4318 0.508)
			(layers "B.Cu" "B.Mask" "B.Paste")
			(net "PRSNT_SWB_N")
		)
		(pad "3" smd rect
			(at 0.94996 0.649986 270)
			(size 0.4318 0.508)
			(layers "B.Cu" "B.Mask" "B.Paste")
			(net "PRSNT_SWB_ISO_N")
		)
		(pad "4" smd rect
			(at -0.94996 0.649986 270)
			(size 0.4318 0.508)
			(layers "B.Cu" "B.Mask" "B.Paste")
			(net "GND")
		)
		(pad "5" smd rect
			(at -0.94996 0 270)
			(size 0.4318 0.508)
			(layers "B.Cu" "B.Mask" "B.Paste")
			(net "PRSNT_SWB")
		)
		(pad "6" smd rect
			(at -0.94996 -0.649986 270)
			(size 0.4318 0.508)
			(layers "B.Cu" "B.Mask" "B.Paste")
			(net "PRSNT_SWB")
		)
	)
)
